#ISCELL
  mstr_misc dns *
  *
#ISCELL
  mstr_symbols intel_corp_bpage *
  *
#ISCELL
  mstr_standard offpage *
  page202_i1
#ISCELL
  mstr_standard offpage *
  page202_i10
#ISCELL
  mstr_standard offpage *
  page202_i11
#ISCELL
  mstr_standard offpage *
  page202_i12
#ISCELL
  mstr_symbols gnd *
  page202_i13
#CELL
  mstr_discrete cap *
  page202_i18
#CELL
  dev_discrete cap_a *
  page202_i19
#ISCELL
  mstr_standard offpage *
  page202_i2
#CELL
  mstr_discrete cap *
  page202_i22
#CELL
  mstr_discrete cap *
  page202_i24
#CELL
  dev_discrete cap_a *
  page202_i25
#ISCELL
  mstr_symbols pvccin_cpu0 *
  page202_i26
#CELL
  dev_discrete cap_a *
  page202_i27
#ISCELL
  mstr_symbols gnd *
  page202_i28
#CELL
  mstr_discrete inductor *
  page202_i29
#ISCELL
  mstr_standard offpage *
  page202_i3
#ISCELL
  mstr_symbols gnd *
  page202_i30
#CELL
  mstr_discrete cap *
  page202_i32
#CELL
  mstr_discrete res *
  page202_i33
#CELL
  mstr_discrete cap *
  page202_i34
#CELL
  dev_discrete cap_a *
  page202_i35
#CELL
  mstr_discrete cap *
  page202_i36
#CELL
  mstr_discrete cap *
  page202_i37
#CELL
  mstr_discrete cap *
  page202_i38
#CELL
  mstr_discrete res *
  page202_i39
#ISCELL
  mstr_symbols pvccin_cpu0 *
  page202_i4
#ISCELL
  mstr_standard offpage *
  page202_i40
#ISCELL
  mstr_symbols vcc_core *
  page202_i41
#CELL
  mstr_discrete cap *
  page202_i42
#ISCELL
  mstr_symbols gnd *
  page202_i43
#ISCELL
  mstr_symbols vcc_core *
  page202_i44
#CELL
  mstr_discrete cap *
  page202_i45
#CELL
  dev_discrete cap_a *
  page202_i46
#CELL
  mstr_discrete cap *
  page202_i47
#CELL
  mstr_discrete cap *
  page202_i48
#CELL
  mstr_discrete cap *
  page202_i49
#CELL
  mstr_discrete inductor *
  page202_i5
#ISCELL
  mstr_standard offpage *
  page202_i50
#CELL
  mstr_discrete cap *
  page202_i51
#ISCELL
  mstr_symbols gnd *
  page202_i52
#ISCELL
  mstr_symbols p5v_stby *
  page202_i59
#ISCELL
  mstr_symbols p5v_stby *
  page202_i60
#CELL
  dev_discrete cap_a *
  page202_i61
#CELL
  dev_discrete cap_a *
  page202_i62
#CELL
  mstr_discrete ir354xx *
  page202_i63
#CELL
  mstr_discrete ir354xx *
  page202_i64
#CELL
  mstr_discrete res *
  page202_i65
#ISCELL
  mstr_symbols gnd *
  page202_i66
#CELL
  mstr_discrete res *
  page202_i67
#ISCELL
  mstr_symbols gnd *
  page202_i68
#CELL
  dev_discrete cap_a *
  page202_i70
#ISCELL
  mstr_symbols gnd *
  page202_i71
#ISCELL
  mstr_symbols gnd *
  page202_i73
#CELL
  w_hdl 3d01r5f-gp *
  page202_i75
#CELL
  w_hdl sc2k2p50v3kx-gp *
  page202_i76
#ISCELL
  mstr_symbols gnd *
  page202_i77
#CELL
  mstr_discrete cap *
  page202_i78
#ISCELL
  mstr_symbols gnd *
  page202_i8
#ISCELL
  mstr_symbols gnd *
  page202_i80
#CELL
  dev_discrete cap_a *
  page202_i81
#CELL
  w_hdl sc2k2p50v3kx-gp *
  page202_i82
#CELL
  w_hdl 3d01r5f-gp *
  page202_i83
#ISCELL
  mstr_symbols gnd *
  page202_i84
#ISCELL
  mstr_symbols gnd *
  page202_i86
#CELL
  mstr_discrete cap *
  page202_i87
#CELL
  mstr_discrete res *
  page202_i88
#CELL
  mstr_discrete res *
  page202_i89
#CELL
  dev_discrete cap_a *
  page202_i9
